# T6G (Grand Teton) — schematic netlist excerpt (pin names and nets, part order shuffled) for the footprints in the layout excerpt that follows; sources: Cadence DE-HDL packaged netlist, KiCad conversion of 04192023_DAF0TMB3IC0_F0TG_MB_C_brd_V02_OCP.brd

PC6580_2  Q_CAP  22UF 16V 20% X6S  pkg C0805  page 363 : A = SW_P12V_AUX_P0V9_RETIMER_CPU0_FLT ; B = GND
C2130  Q_CAP  22UF 4V 20% X6S  pkg C0402  page 68 : A = PVDDCR_SOC_P0 ; B = GND
R180  Q_RES  0 5% CHIP  pkg 0402LF  page 82 : A = CPU0_SP5R1 ; B = FM_CPU0_SP5R1

(kicad_pcb
	(version 20260206)
	(generator "pcbnew")
	(generator_version "10.0")
	(general
		(thickness 1.6)
		(legacy_teardrops no)
	)
	(paper "A4")
	(title_block
		(title "04192023_DAF0TMB3IC0_F0TG_MB_C_brd_V02_OCP.brd")
		(comment 1 "Grand Teton / footprints 5626-5628 of 8354")
	)
	(layers
		(0 "F.Cu" signal "TOP")
		(4 "In1.Cu" signal "GND")
		(6 "In2.Cu" signal "IN1")
		(8 "In3.Cu" signal "GND1")
		(10 "In4.Cu" signal "IN2")
		(12 "In5.Cu" signal "GND2")
		(14 "In6.Cu" signal "IN3")
		(16 "In7.Cu" signal "GND3")
		(18 "In8.Cu" signal "VCC")
		(20 "In9.Cu" signal "VCC1")
		(22 "In10.Cu" signal "GND4")
		(24 "In11.Cu" signal "IN4")
		(26 "In12.Cu" signal "GND5")
		(28 "In13.Cu" signal "IN5")
		(30 "In14.Cu" signal "GND6")
		(32 "In15.Cu" signal "IN6")
		(34 "In16.Cu" signal "GND7")
		(2 "B.Cu" signal "BOTTOM")
		(9 "F.Adhes" user "F.Adhesive")
		(11 "B.Adhes" user "B.Adhesive")
		(13 "F.Paste" user "Package Geometry/Pastemask Top")
		(15 "B.Paste" user "Package Geometry/Pastemask Bottom")
		(5 "F.SilkS" user "Ref Des/Silkscreen Top")
		(7 "B.SilkS" user "Ref Des/Silkscreen Bottom")
		(1 "F.Mask" user "Board Geometry/Soldermask Top")
		(3 "B.Mask" user "Board Geometry/Soldermask Bottom")
		(17 "Dwgs.User" user "User.Drawings")
		(19 "Cmts.User" user "User.Comments")
		(21 "Eco1.User" user "User.Eco1")
		(23 "Eco2.User" user "User.Eco2")
		(25 "Edge.Cuts" user "Board Geometry/Outline")
		(27 "Margin" user)
		(31 "F.CrtYd" user "Package Geometry/Place Bound Top")
		(29 "B.CrtYd" user "Package Geometry/Place Bound Bottom")
		(35 "F.Fab" user "Ref Des/Assembly Top")
		(33 "B.Fab" user "Ref Des/Assembly Bottom")
	)
	(footprint ""
		(layer "B.Cu")
		(at 369.646454 -255.84531)
		(property "Reference" "C2130"
			(at 0 0 0)
			(layer "B.SilkS")
			(hide yes)
			(effects
				(font
					(size 1.27 1.27)
				)
				(justify mirror)
			)
		)
		(property "Value" ""
			(at 0 0 0)
			(layer "B.Fab")
			(effects
				(font
					(size 1.27 1.27)
				)
				(justify mirror)
			)
		)
		(duplicate_pad_numbers_are_jumpers no)
		(fp_line
			(start -0.7874 -0.4064)
			(end -0.7874 0.4064)
			(stroke
				(width 0.1524)
				(type default)
			)
			(layer "B.SilkS")
		)
		(fp_line
			(start -0.7874 0.4064)
			(end 0.7874 0.4064)
			(stroke
				(width 0.1524)
				(type default)
			)
			(layer "B.SilkS")
		)
		(fp_line
			(start 0.7874 -0.4064)
			(end -0.7874 -0.4064)
			(stroke
				(width 0.1524)
				(type default)
			)
			(layer "B.SilkS")
		)
		(fp_line
			(start 0.7874 0.4064)
			(end 0.7874 -0.4064)
			(stroke
				(width 0.1524)
				(type default)
			)
			(layer "B.SilkS")
		)
		(fp_line
			(start -0.67945 -0.3048)
			(end -0.67945 0.3048)
			(stroke
				(width 0.1)
				(type default)
			)
			(layer "B.Fab")
		)
		(fp_line
			(start -0.67945 0.3048)
			(end -0.120396 0.3048)
			(stroke
				(width 0.1)
				(type default)
			)
			(layer "B.Fab")
		)
		(fp_line
			(start -0.12065 -0.3048)
			(end -0.67945 -0.3048)
			(stroke
				(width 0.1)
				(type default)
			)
			(layer "B.Fab")
		)
		(fp_line
			(start -0.12065 -0.2794)
			(end -0.12065 -0.3048)
			(stroke
				(width 0.1)
				(type default)
			)
			(layer "B.Fab")
		)
		(fp_line
			(start -0.120396 0.2794)
			(end 0.12065 0.2794)
			(stroke
				(width 0.1)
				(type default)
			)
			(layer "B.Fab")
		)
		(fp_line
			(start -0.120396 0.3048)
			(end -0.120396 0.2794)
			(stroke
				(width 0.1)
				(type default)
			)
			(layer "B.Fab")
		)
		(fp_line
			(start 0.12065 -0.305054)
			(end 0.12065 -0.2794)
			(stroke
				(width 0.1)
				(type default)
			)
			(layer "B.Fab")
		)
		(fp_line
			(start 0.12065 -0.2794)
			(end -0.12065 -0.2794)
			(stroke
				(width 0.1)
				(type default)
			)
			(layer "B.Fab")
		)
		(fp_line
			(start 0.12065 0.2794)
			(end 0.12065 0.3048)
			(stroke
				(width 0.1)
				(type default)
			)
			(layer "B.Fab")
		)
		(fp_line
			(start 0.12065 0.3048)
			(end 0.67945 0.3048)
			(stroke
				(width 0.1)
				(type default)
			)
			(layer "B.Fab")
		)
		(fp_line
			(start 0.67945 -0.305054)
			(end 0.12065 -0.305054)
			(stroke
				(width 0.1)
				(type default)
			)
			(layer "B.Fab")
		)
		(fp_line
			(start 0.67945 0.3048)
			(end 0.67945 -0.305054)
			(stroke
				(width 0.1)
				(type default)
			)
			(layer "B.Fab")
		)
		(pad "1" smd circle
			(at 0.40005 0 180)
			(size 0 0)
			(layers "B.Cu" "B.Mask" "B.Paste")
			(net "PVDDCR_SOC_P0")
		)
		(pad "2" smd circle
			(at -0.40005 0 180)
			(size 0 0)
			(layers "B.Cu" "B.Mask" "B.Paste")
			(net "GND")
		)
	)
	(footprint ""
		(layer "B.Cu")
		(at 457.347066 -397.05407 90)
		(property "Reference" "PC6580_2"
			(at 0 0 90)
			(layer "B.SilkS")
			(hide yes)
			(effects
				(font
					(size 1.27 1.27)
				)
				(justify mirror)
			)
		)
		(property "Value" ""
			(at 0 0 90)
			(layer "B.Fab")
			(effects
				(font
					(size 1.27 1.27)
				)
				(justify mirror)
			)
		)
		(duplicate_pad_numbers_are_jumpers no)
		(fp_line
			(start 1.524 -0.762)
			(end -1.524 -0.762)
			(stroke
				(width 0.1524)
				(type default)
			)
			(layer "B.SilkS")
		)
		(fp_line
			(start -1.524 -0.762)
			(end -1.524 0.762)
			(stroke
				(width 0.1524)
				(type default)
			)
			(layer "B.SilkS")
		)
		(fp_line
			(start 1.524 0.762)
			(end 1.524 -0.762)
			(stroke
				(width 0.1524)
				(type default)
			)
			(layer "B.SilkS")
		)
		(fp_line
			(start -1.524 0.762)
			(end 1.524 0.762)
			(stroke
				(width 0.1524)
				(type default)
			)
			(layer "B.SilkS")
		)
		(fp_line
			(start 1.1049 -0.724916)
			(end 1.1049 0.724916)
			(stroke
				(width 0.1)
				(type default)
			)
			(layer "B.Fab")
		)
		(fp_line
			(start -1.1049 -0.724916)
			(end 1.1049 -0.724916)
			(stroke
				(width 0.1)
				(type default)
			)
			(layer "B.Fab")
		)
		(fp_line
			(start 1.1049 0.724916)
			(end -1.1049 0.724916)
			(stroke
				(width 0.1)
				(type default)
			)
			(layer "B.Fab")
		)
		(fp_line
			(start -1.1049 0.724916)
			(end -1.1049 -0.724916)
			(stroke
				(width 0.1)
				(type default)
			)
			(layer "B.Fab")
		)
		(pad "1" smd rect
			(at 0.889 0 90)
			(size 1.016 1.27)
			(layers "B.Cu" "B.Mask" "B.Paste")
			(net "SW_P12V_AUX_P0V9_RETIMER_CPU0_FLT")
		)
		(pad "2" smd rect
			(at -0.889 0 90)
			(size 1.016 1.27)
			(layers "B.Cu" "B.Mask" "B.Paste")
			(net "GND")
		)
	)
	(footprint ""
		(layer "B.Cu")
		(at 186.806078 -97.085912 -90)
		(property "Reference" "R180"
			(at 0 0 90)
			(layer "B.SilkS")
			(hide yes)
			(effects
				(font
					(size 1.27 1.27)
				)
				(justify mirror)
			)
		)
		(property "Value" ""
			(at 0 0 90)
			(layer "B.Fab")
			(effects
				(font
					(size 1.27 1.27)
				)
				(justify mirror)
			)
		)
		(duplicate_pad_numbers_are_jumpers no)
		(fp_line
			(start -0.7874 0.4064)
			(end 0.7874 0.4064)
			(stroke
				(width 0.1524)
				(type default)
			)
			(layer "B.SilkS")
		)
		(fp_line
			(start 0.7874 0.4064)
			(end 0.7874 -0.4064)
			(stroke
				(width 0.1524)
				(type default)
			)
			(layer "B.SilkS")
		)
		(fp_line
			(start -0.7874 -0.4064)
			(end -0.7874 0.4064)
			(stroke
				(width 0.1524)
				(type default)
			)
			(layer "B.SilkS")
		)
		(fp_line
			(start 0.7874 -0.4064)
			(end -0.7874 -0.4064)
			(stroke
				(width 0.1524)
				(type default)
			)
			(layer "B.SilkS")
		)
		(fp_line
			(start -0.67945 0.3048)
			(end -0.120396 0.3048)
			(stroke
				(width 0.1)
				(type default)
			)
			(layer "B.Fab")
		)
		(fp_line
			(start -0.120396 0.3048)
			(end -0.120396 0.2794)
			(stroke
				(width 0.1)
				(type default)
			)
			(layer "B.Fab")
		)
		(fp_line
			(start 0.12065 0.3048)
			(end 0.67945 0.3048)
			(stroke
				(width 0.1)
				(type default)
			)
			(layer "B.Fab")
		)
		(fp_line
			(start 0.67945 0.3048)
			(end 0.67945 -0.305054)
			(stroke
				(width 0.1)
				(type default)
			)
			(layer "B.Fab")
		)
		(fp_line
			(start -0.120396 0.2794)
			(end 0.12065 0.2794)
			(stroke
				(width 0.1)
				(type default)
			)
			(layer "B.Fab")
		)
		(fp_line
			(start 0.12065 0.2794)
			(end 0.12065 0.3048)
			(stroke
				(width 0.1)
				(type default)
			)
			(layer "B.Fab")
		)
		(fp_line
			(start -0.12065 -0.2794)
			(end -0.12065 -0.3048)
			(stroke
				(width 0.1)
				(type default)
			)
			(layer "B.Fab")
		)
		(fp_line
			(start 0.12065 -0.2794)
			(end -0.12065 -0.2794)
			(stroke
				(width 0.1)
				(type default)
			)
			(layer "B.Fab")
		)
		(fp_line
			(start -0.67945 -0.3048)
			(end -0.67945 0.3048)
			(stroke
				(width 0.1)
				(type default)
			)
			(layer "B.Fab")
		)
		(fp_line
			(start -0.12065 -0.3048)
			(end -0.67945 -0.3048)
			(stroke
				(width 0.1)
				(type default)
			)
			(layer "B.Fab")
		)
		(fp_line
			(start 0.12065 -0.305054)
			(end 0.12065 -0.2794)
			(stroke
				(width 0.1)
				(type default)
			)
			(layer "B.Fab")
		)
		(fp_line
			(start 0.67945 -0.305054)
			(end 0.12065 -0.305054)
			(stroke
				(width 0.1)
				(type default)
			)
			(layer "B.Fab")
		)
		(pad "1" smd circle
			(at 0.40005 0 90)
			(size 0 0)
			(layers "B.Cu" "B.Mask" "B.Paste")
			(net "CPU0_SP5R1")
		)
		(pad "2" smd circle
			(at -0.40005 0 90)
			(size 0 0)
			(layers "B.Cu" "B.Mask" "B.Paste")
			(net "FM_CPU0_SP5R1")
		)
	)
)
